M48
INCH,TZ
T01C.008
T02C.01
T03C.012
T04C.016
T05C.04
T06C.044
T07C.063
T08C.065
T09C.086
T010C.119
T011C.126
T012C.14
;EXTENTS: -23.869 -24.991 20.769  22.454  
;LEADER: 12 
;HEADER: 
;CODE  : ASCII 
;FILE  : 13130-1b.rou for board 13130-1b.brd
%
G90
F1
M16
T011
M16
G00X347047Y231103
G40
M15
G01X353347
M16
G40
M30
